(kicad_pcb
	(version 20260206)
	(generator "pcbnew")
	(generator_version "10.0")
	(general
		(thickness 1.6)
		(legacy_teardrops no)
	)
	(paper "A4")
	(title_block
		(title "04192023_DAF0TMB3IC0_F0TG_MB_C_brd_V02_OCP.brd")
		(comment 1 "Grand Teton / footprint 2783 of 8354 (U26), pads 2105-2218 of 6102")
	)
	(layers
		(0 "F.Cu" signal "TOP")
		(4 "In1.Cu" signal "GND")
		(6 "In2.Cu" signal "IN1")
		(8 "In3.Cu" signal "GND1")
		(10 "In4.Cu" signal "IN2")
		(12 "In5.Cu" signal "GND2")
		(14 "In6.Cu" signal "IN3")
		(16 "In7.Cu" signal "GND3")
		(18 "In8.Cu" signal "VCC")
		(20 "In9.Cu" signal "VCC1")
		(22 "In10.Cu" signal "GND4")
		(24 "In11.Cu" signal "IN4")
		(26 "In12.Cu" signal "GND5")
		(28 "In13.Cu" signal "IN5")
		(30 "In14.Cu" signal "GND6")
		(32 "In15.Cu" signal "IN6")
		(34 "In16.Cu" signal "GND7")
		(2 "B.Cu" signal "BOTTOM")
		(9 "F.Adhes" user "F.Adhesive")
		(11 "B.Adhes" user "B.Adhesive")
		(13 "F.Paste" user "Package Geometry/Pastemask Top")
		(15 "B.Paste" user "Package Geometry/Pastemask Bottom")
		(5 "F.SilkS" user "Ref Des/Silkscreen Top")
		(7 "B.SilkS" user "Ref Des/Silkscreen Bottom")
		(1 "F.Mask" user "Board Geometry/Soldermask Top")
		(3 "B.Mask" user "Board Geometry/Soldermask Bottom")
		(17 "Dwgs.User" user "User.Drawings")
		(19 "Cmts.User" user "User.Comments")
		(21 "Eco1.User" user "User.Eco1")
		(23 "Eco2.User" user "User.Eco2")
		(25 "Edge.Cuts" user "Board Geometry/Outline")
		(27 "Margin" user)
		(31 "F.CrtYd" user "Package Geometry/Place Bound Top")
		(29 "B.CrtYd" user "Package Geometry/Place Bound Bottom")
		(35 "F.Fab" user "Ref Des/Assembly Top")
		(33 "B.Fab" user "Ref Des/Assembly Bottom")
	)
	(footprint ""
		(layer "F.Cu")
		(at 111.927894 -258.880356 180)
		(property "Reference" "U26"
			(at -45.05579 -61.794136 0)
			(unlocked yes)
			(layer "F.SilkS")
			(effects
				(font
					(size 0.7874 0.5842)
					(thickness 0.1524)
				)
			)
		)
		(property "Value" ""
			(at 0 0 180)
			(layer "F.Fab")
			(effects
				(font
					(size 1.27 1.27)
				)
			)
		)
		(duplicate_pad_numbers_are_jumpers no)
		(pad "BM18" smd circle
			(at -18.949924 6.839966 180)
			(size 0.450088 0.450088)
			(layers "F.Cu" "F.Mask" "F.Paste")
			(net "M_J_CPU1_SB_CS_N<0>")
		)
		(pad "BM19" smd circle
			(at -18.010124 6.839966 180)
			(size 0.450088 0.450088)
			(layers "F.Cu" "F.Mask" "F.Paste")
			(net "PVDD11_S3_P1")
		)
		(pad "BM20" smd circle
			(at -17.07007 6.839966 180)
			(size 0.450088 0.450088)
			(layers "F.Cu" "F.Mask" "F.Paste")
			(net "Net_2060")
		)
		(pad "BM21" smd circle
			(at -16.130016 6.839966 180)
			(size 0.450088 0.450088)
			(layers "F.Cu" "F.Mask" "F.Paste")
			(net "M_I_CPU1_SB_CS_N<0>")
		)
		(pad "BM22" smd circle
			(at -15.189962 6.839966 180)
			(size 0.450088 0.450088)
			(layers "F.Cu" "F.Mask" "F.Paste")
			(net "PVDD11_S3_P1")
		)
		(pad "BM23" smd circle
			(at -14.249908 6.839966 180)
			(size 0.450088 0.450088)
			(layers "F.Cu" "F.Mask" "F.Paste")
			(net "GND")
		)
		(pad "BM24" smd circle
			(at -13.310108 6.839966 180)
			(size 0.450088 0.450088)
			(layers "F.Cu" "F.Mask" "F.Paste")
			(net "PVDD11_S3_P1")
		)
		(pad "BM25" smd circle
			(at -12.370054 6.839966 180)
			(size 0.450088 0.450088)
			(layers "F.Cu" "F.Mask" "F.Paste")
			(net "GND")
		)
		(pad "BM26" smd circle
			(at -11.43 6.839966 180)
			(size 0.450088 0.450088)
			(layers "F.Cu" "F.Mask" "F.Paste")
			(net "PVDD11_S3_P1")
		)
		(pad "BM27" smd circle
			(at -10.489946 6.839966 180)
			(size 0.450088 0.450088)
			(layers "F.Cu" "F.Mask" "F.Paste")
			(net "GND")
		)
		(pad "BM28" smd circle
			(at -9.549892 6.839966 180)
			(size 0.450088 0.450088)
			(layers "F.Cu" "F.Mask" "F.Paste")
			(net "PVDD11_S3_P1")
		)
		(pad "BM29" smd circle
			(at -8.610092 6.839966 180)
			(size 0.450088 0.450088)
			(layers "F.Cu" "F.Mask" "F.Paste")
			(net "GND")
		)
		(pad "BM30" smd circle
			(at -7.670038 6.839966 180)
			(size 0.450088 0.450088)
			(layers "F.Cu" "F.Mask" "F.Paste")
			(net "PVDD11_S3_P1")
		)
		(pad "BM31" smd circle
			(at -6.729984 6.839966 180)
			(size 0.450088 0.450088)
			(layers "F.Cu" "F.Mask" "F.Paste")
			(net "GND")
		)
		(pad "BM32" smd circle
			(at -5.78993 6.839966 180)
			(size 0.450088 0.450088)
			(layers "F.Cu" "F.Mask" "F.Paste")
			(net "PVDD11_S3_P1")
		)
		(pad "BM33" smd circle
			(at -4.849876 6.839966 180)
			(size 0.450088 0.450088)
			(layers "F.Cu" "F.Mask" "F.Paste")
			(net "GND")
		)
		(pad "BM34" smd circle
			(at -3.910076 6.839966 180)
			(size 0.450088 0.450088)
			(layers "F.Cu" "F.Mask" "F.Paste")
			(net "PVDD11_S3_P1")
		)
		(pad "BM35" smd circle
			(at -2.970022 6.839966 180)
			(size 0.450088 0.450088)
			(layers "F.Cu" "F.Mask" "F.Paste")
			(net "GND")
		)
		(pad "BM36" smd circle
			(at -2.029968 6.839966 180)
			(size 0.450088 0.450088)
			(layers "F.Cu" "F.Mask" "F.Paste")
			(net "PVDD11_S3_P1")
		)
		(pad "BM37" smd circle
			(at -1.089914 6.839966 180)
			(size 0.450088 0.450088)
			(layers "F.Cu" "F.Mask" "F.Paste")
			(net "GND")
		)
		(pad "BM39" smd circle
			(at 0.78994 6.839966 180)
			(size 0.450088 0.450088)
			(layers "F.Cu" "F.Mask" "F.Paste")
			(net "PVDD11_S3_P1")
		)
		(pad "BM40" smd circle
			(at 1.729994 6.839966 180)
			(size 0.450088 0.450088)
			(layers "F.Cu" "F.Mask" "F.Paste")
			(net "GND")
		)
		(pad "BM41" smd circle
			(at 2.670048 6.839966 180)
			(size 0.450088 0.450088)
			(layers "F.Cu" "F.Mask" "F.Paste")
			(net "PVDD11_S3_P1")
		)
		(pad "BM42" smd circle
			(at 3.610102 6.839966 180)
			(size 0.450088 0.450088)
			(layers "F.Cu" "F.Mask" "F.Paste")
			(net "GND")
		)
		(pad "BM43" smd circle
			(at 4.549902 6.839966 180)
			(size 0.450088 0.450088)
			(layers "F.Cu" "F.Mask" "F.Paste")
			(net "PVDD11_S3_P1")
		)
		(pad "BM44" smd circle
			(at 5.489956 6.839966 180)
			(size 0.450088 0.450088)
			(layers "F.Cu" "F.Mask" "F.Paste")
			(net "GND")
		)
		(pad "BM45" smd circle
			(at 6.43001 6.839966 180)
			(size 0.450088 0.450088)
			(layers "F.Cu" "F.Mask" "F.Paste")
			(net "PVDD11_S3_P1")
		)
		(pad "BM46" smd circle
			(at 7.370064 6.839966 180)
			(size 0.450088 0.450088)
			(layers "F.Cu" "F.Mask" "F.Paste")
			(net "GND")
		)
		(pad "BM47" smd circle
			(at 8.310118 6.839966 180)
			(size 0.450088 0.450088)
			(layers "F.Cu" "F.Mask" "F.Paste")
			(net "PVDD11_S3_P1")
		)
		(pad "BM48" smd circle
			(at 9.249918 6.839966 180)
			(size 0.450088 0.450088)
			(layers "F.Cu" "F.Mask" "F.Paste")
			(net "GND")
		)
		(pad "BM49" smd circle
			(at 10.189972 6.839966 180)
			(size 0.450088 0.450088)
			(layers "F.Cu" "F.Mask" "F.Paste")
			(net "PVDD11_S3_P1")
		)
		(pad "BM50" smd circle
			(at 11.130026 6.839966 180)
			(size 0.450088 0.450088)
			(layers "F.Cu" "F.Mask" "F.Paste")
			(net "GND")
		)
		(pad "BM51" smd circle
			(at 12.07008 6.839966 180)
			(size 0.450088 0.450088)
			(layers "F.Cu" "F.Mask" "F.Paste")
			(net "PVDDIO_P1")
		)
		(pad "BM52" smd circle
			(at 13.00988 6.839966 180)
			(size 0.450088 0.450088)
			(layers "F.Cu" "F.Mask" "F.Paste")
			(net "GND")
		)
		(pad "BM53" smd circle
			(at 13.949934 6.839966 180)
			(size 0.450088 0.450088)
			(layers "F.Cu" "F.Mask" "F.Paste")
			(net "PVDDIO_P1")
		)
		(pad "BM54" smd circle
			(at 14.889988 6.839966 180)
			(size 0.450088 0.450088)
			(layers "F.Cu" "F.Mask" "F.Paste")
			(net "GND")
		)
		(pad "BM55" smd circle
			(at 15.830042 6.839966 180)
			(size 0.450088 0.450088)
			(layers "F.Cu" "F.Mask" "F.Paste")
			(net "M_C_CPU1_SB_CS_N<0>")
		)
		(pad "BM56" smd circle
			(at 16.770096 6.839966 180)
			(size 0.450088 0.450088)
			(layers "F.Cu" "F.Mask" "F.Paste")
			(net "Net_2012")
		)
		(pad "BM57" smd circle
			(at 17.709896 6.839966 180)
			(size 0.450088 0.450088)
			(layers "F.Cu" "F.Mask" "F.Paste")
			(net "PVDDIO_P1")
		)
		(pad "BM58" smd circle
			(at 18.64995 6.839966 180)
			(size 0.450088 0.450088)
			(layers "F.Cu" "F.Mask" "F.Paste")
			(net "M_D_CPU1_SB_CS_N<0>")
		)
		(pad "BM59" smd circle
			(at 19.590004 6.839966 180)
			(size 0.450088 0.450088)
			(layers "F.Cu" "F.Mask" "F.Paste")
			(net "GND")
		)
		(pad "BM60" smd circle
			(at 20.530058 6.839966 180)
			(size 0.450088 0.450088)
			(layers "F.Cu" "F.Mask" "F.Paste")
			(net "Net_2020")
		)
		(pad "BM61" smd circle
			(at 21.470112 6.839966 180)
			(size 0.450088 0.450088)
			(layers "F.Cu" "F.Mask" "F.Paste")
			(net "GND")
		)
		(pad "BM62" smd circle
			(at 22.409912 6.839966 180)
			(size 0.450088 0.450088)
			(layers "F.Cu" "F.Mask" "F.Paste")
			(net "M_B_CPU1_SB_CS_N<0>")
		)
		(pad "BM63" smd circle
			(at 23.349966 6.839966 180)
			(size 0.450088 0.450088)
			(layers "F.Cu" "F.Mask" "F.Paste")
			(net "Net_2004")
		)
		(pad "BM64" smd circle
			(at 24.29002 6.839966 180)
			(size 0.450088 0.450088)
			(layers "F.Cu" "F.Mask" "F.Paste")
			(net "PVDDIO_P1")
		)
		(pad "BM65" smd circle
			(at 25.230074 6.839966 180)
			(size 0.450088 0.450088)
			(layers "F.Cu" "F.Mask" "F.Paste")
			(net "M_F_CPU1_SB_CS_N<0>")
		)
		(pad "BM66" smd circle
			(at 26.170128 6.839966 180)
			(size 0.450088 0.450088)
			(layers "F.Cu" "F.Mask" "F.Paste")
			(net "GND")
		)
		(pad "BM67" smd circle
			(at 27.109928 6.839966 180)
			(size 0.450088 0.450088)
			(layers "F.Cu" "F.Mask" "F.Paste")
			(net "Net_2036")
		)
		(pad "BM68" smd circle
			(at 28.049982 6.839966 180)
			(size 0.450088 0.450088)
			(layers "F.Cu" "F.Mask" "F.Paste")
			(net "GND")
		)
		(pad "BM69" smd circle
			(at 28.990036 6.839966 180)
			(size 0.450088 0.450088)
			(layers "F.Cu" "F.Mask" "F.Paste")
			(net "M_E_CPU1_SB_CS_N<0>")
		)
		(pad "BM70" smd circle
			(at 29.93009 6.839966 180)
			(size 0.450088 0.450088)
			(layers "F.Cu" "F.Mask" "F.Paste")
			(net "Net_2028")
		)
		(pad "BM71" smd circle
			(at 30.86989 6.839966 180)
			(size 0.450088 0.450088)
			(layers "F.Cu" "F.Mask" "F.Paste")
			(net "PVDDIO_P1")
		)
		(pad "BM72" smd circle
			(at 31.809944 6.839966 180)
			(size 0.450088 0.450088)
			(layers "F.Cu" "F.Mask" "F.Paste")
			(net "M_A_CPU1_SB_CS_N<0>")
		)
		(pad "BM73" smd circle
			(at 32.749998 6.839966 180)
			(size 0.450088 0.450088)
			(layers "F.Cu" "F.Mask" "F.Paste")
			(net "GND")
		)
		(pad "BM74" smd circle
			(at 33.690052 6.839966 180)
			(size 0.450088 0.450088)
			(layers "F.Cu" "F.Mask" "F.Paste")
			(net "Net_1996")
		)
		(pad "BN1" smd circle
			(at -34.459926 7.649972 180)
			(size 0.450088 0.450088)
			(layers "F.Cu" "F.Mask" "F.Paste")
			(net "GND")
		)
		(pad "BN2" smd circle
			(at -33.519872 7.649972 180)
			(size 0.450088 0.450088)
			(layers "F.Cu" "F.Mask" "F.Paste")
			(net "M_G_CPU1_SB_CS_N<1>")
		)
		(pad "BN3" smd circle
			(at -32.580072 7.649972 180)
			(size 0.450088 0.450088)
			(layers "F.Cu" "F.Mask" "F.Paste")
			(net "M_G_CPU1_SA_RSP<0>")
		)
		(pad "BN4" smd circle
			(at -31.640018 7.649972 180)
			(size 0.450088 0.450088)
			(layers "F.Cu" "F.Mask" "F.Paste")
			(net "GND")
		)
		(pad "BN5" smd circle
			(at -30.699964 7.649972 180)
			(size 0.450088 0.450088)
			(layers "F.Cu" "F.Mask" "F.Paste")
			(net "M_K_CPU1_SB_CS_N<1>")
		)
		(pad "BN6" smd circle
			(at -29.75991 7.649972 180)
			(size 0.450088 0.450088)
			(layers "F.Cu" "F.Mask" "F.Paste")
			(net "GND")
		)
		(pad "BN7" smd circle
			(at -28.82011 7.649972 180)
			(size 0.450088 0.450088)
			(layers "F.Cu" "F.Mask" "F.Paste")
			(net "M_K_CPU1_SA_RSP<0>")
		)
		(pad "BN8" smd circle
			(at -27.880056 7.649972 180)
			(size 0.450088 0.450088)
			(layers "F.Cu" "F.Mask" "F.Paste")
			(net "GND")
		)
		(pad "BN9" smd circle
			(at -26.940002 7.649972 180)
			(size 0.450088 0.450088)
			(layers "F.Cu" "F.Mask" "F.Paste")
			(net "M_L_CPU1_SB_CS_N<1>")
		)
		(pad "BN10" smd circle
			(at -25.999948 7.649972 180)
			(size 0.450088 0.450088)
			(layers "F.Cu" "F.Mask" "F.Paste")
			(net "M_L_CPU1_SA_RSP<0>")
		)
		(pad "BN11" smd circle
			(at -25.059894 7.649972 180)
			(size 0.450088 0.450088)
			(layers "F.Cu" "F.Mask" "F.Paste")
			(net "GND")
		)
		(pad "BN12" smd circle
			(at -24.120094 7.649972 180)
			(size 0.450088 0.450088)
			(layers "F.Cu" "F.Mask" "F.Paste")
			(net "M_H_CPU1_SB_CS_N<1>")
		)
		(pad "BN13" smd circle
			(at -23.18004 7.649972 180)
			(size 0.450088 0.450088)
			(layers "F.Cu" "F.Mask" "F.Paste")
			(net "GND")
		)
		(pad "BN14" smd circle
			(at -22.239986 7.649972 180)
			(size 0.450088 0.450088)
			(layers "F.Cu" "F.Mask" "F.Paste")
			(net "M_H_CPU1_SA_RSP<0>")
		)
		(pad "BN15" smd circle
			(at -21.299932 7.649972 180)
			(size 0.450088 0.450088)
			(layers "F.Cu" "F.Mask" "F.Paste")
			(net "GND")
		)
		(pad "BN16" smd circle
			(at -20.359878 7.649972 180)
			(size 0.450088 0.450088)
			(layers "F.Cu" "F.Mask" "F.Paste")
			(net "M_J_CPU1_SB_CS_N<1>")
		)
		(pad "BN17" smd circle
			(at -19.420078 7.649972 180)
			(size 0.450088 0.450088)
			(layers "F.Cu" "F.Mask" "F.Paste")
			(net "M_J_CPU1_SA_RSP<0>")
		)
		(pad "BN18" smd circle
			(at -18.480024 7.649972 180)
			(size 0.450088 0.450088)
			(layers "F.Cu" "F.Mask" "F.Paste")
			(net "GND")
		)
		(pad "BN19" smd circle
			(at -17.53997 7.649972 180)
			(size 0.450088 0.450088)
			(layers "F.Cu" "F.Mask" "F.Paste")
			(net "M_I_CPU1_SB_CS_N<1>")
		)
		(pad "BN20" smd circle
			(at -16.599916 7.649972 180)
			(size 0.450088 0.450088)
			(layers "F.Cu" "F.Mask" "F.Paste")
			(net "GND")
		)
		(pad "BN21" smd circle
			(at -15.660116 7.649972 180)
			(size 0.450088 0.450088)
			(layers "F.Cu" "F.Mask" "F.Paste")
			(net "M_I_CPU1_SA_RSP<0>")
		)
		(pad "BN22" smd circle
			(at -14.720062 7.649972 180)
			(size 0.450088 0.450088)
			(layers "F.Cu" "F.Mask" "F.Paste")
			(net "GND")
		)
		(pad "BN23" smd circle
			(at -13.780008 7.649972 180)
			(size 0.450088 0.450088)
			(layers "F.Cu" "F.Mask" "F.Paste")
			(net "CPU1_VDDBT_RTC_G")
		)
		(pad "BN24" smd circle
			(at -12.839954 7.649972 180)
			(size 0.450088 0.450088)
			(layers "F.Cu" "F.Mask" "F.Paste")
			(net "GND")
		)
		(pad "BN25" smd circle
			(at -11.8999 7.649972 180)
			(size 0.450088 0.450088)
			(layers "F.Cu" "F.Mask" "F.Paste")
			(net "PVDD11_S3_P1")
		)
		(pad "BN26" smd circle
			(at -10.9601 7.649972 180)
			(size 0.450088 0.450088)
			(layers "F.Cu" "F.Mask" "F.Paste")
			(net "GND")
		)
		(pad "BN27" smd circle
			(at -10.020046 7.649972 180)
			(size 0.450088 0.450088)
			(layers "F.Cu" "F.Mask" "F.Paste")
			(net "PVDDCR_CPU1_P1")
		)
		(pad "BN28" smd circle
			(at -9.079992 7.649972 180)
			(size 0.450088 0.450088)
			(layers "F.Cu" "F.Mask" "F.Paste")
			(net "GND")
		)
		(pad "BN29" smd circle
			(at -8.139938 7.649972 180)
			(size 0.450088 0.450088)
			(layers "F.Cu" "F.Mask" "F.Paste")
			(net "PVDD11_S3_P1")
		)
		(pad "BN30" smd circle
			(at -7.199884 7.649972 180)
			(size 0.450088 0.450088)
			(layers "F.Cu" "F.Mask" "F.Paste")
			(net "GND")
		)
		(pad "BN31" smd circle
			(at -6.260084 7.649972 180)
			(size 0.450088 0.450088)
			(layers "F.Cu" "F.Mask" "F.Paste")
			(net "PVDDCR_CPU1_P1")
		)
		(pad "BN32" smd circle
			(at -5.32003 7.649972 180)
			(size 0.450088 0.450088)
			(layers "F.Cu" "F.Mask" "F.Paste")
			(net "GND")
		)
		(pad "BN33" smd circle
			(at -4.379976 7.649972 180)
			(size 0.450088 0.450088)
			(layers "F.Cu" "F.Mask" "F.Paste")
			(net "PVDD11_S3_P1")
		)
		(pad "BN34" smd circle
			(at -3.439922 7.649972 180)
			(size 0.450088 0.450088)
			(layers "F.Cu" "F.Mask" "F.Paste")
			(net "GND")
		)
		(pad "BN35" smd circle
			(at -2.500122 7.649972 180)
			(size 0.450088 0.450088)
			(layers "F.Cu" "F.Mask" "F.Paste")
			(net "PVDDCR_CPU1_P1")
		)
		(pad "BN36" smd circle
			(at -1.560068 7.649972 180)
			(size 0.450088 0.450088)
			(layers "F.Cu" "F.Mask" "F.Paste")
			(net "GND")
		)
		(pad "BN40" smd circle
			(at 1.260094 7.649972 180)
			(size 0.450088 0.450088)
			(layers "F.Cu" "F.Mask" "F.Paste")
			(net "PVDD11_S3_P1")
		)
		(pad "BN41" smd circle
			(at 2.199894 7.649972 180)
			(size 0.450088 0.450088)
			(layers "F.Cu" "F.Mask" "F.Paste")
			(net "GND")
		)
		(pad "BN42" smd circle
			(at 3.139948 7.649972 180)
			(size 0.450088 0.450088)
			(layers "F.Cu" "F.Mask" "F.Paste")
			(net "PVDDCR_CPU1_P1")
		)
		(pad "BN43" smd circle
			(at 4.080002 7.649972 180)
			(size 0.450088 0.450088)
			(layers "F.Cu" "F.Mask" "F.Paste")
			(net "GND")
		)
		(pad "BN44" smd circle
			(at 5.020056 7.649972 180)
			(size 0.450088 0.450088)
			(layers "F.Cu" "F.Mask" "F.Paste")
			(net "PVDD11_S3_P1")
		)
		(pad "BN45" smd circle
			(at 5.96011 7.649972 180)
			(size 0.450088 0.450088)
			(layers "F.Cu" "F.Mask" "F.Paste")
			(net "GND")
		)
		(pad "BN46" smd circle
			(at 6.89991 7.649972 180)
			(size 0.450088 0.450088)
			(layers "F.Cu" "F.Mask" "F.Paste")
			(net "PVDDCR_CPU1_P1")
		)
		(pad "BN47" smd circle
			(at 7.839964 7.649972 180)
			(size 0.450088 0.450088)
			(layers "F.Cu" "F.Mask" "F.Paste")
			(net "GND")
		)
		(pad "BN48" smd circle
			(at 8.780018 7.649972 180)
			(size 0.450088 0.450088)
			(layers "F.Cu" "F.Mask" "F.Paste")
			(net "PVDD11_S3_P1")
		)
		(pad "BN49" smd circle
			(at 9.720072 7.649972 180)
			(size 0.450088 0.450088)
			(layers "F.Cu" "F.Mask" "F.Paste")
			(net "GND")
		)
		(pad "BN50" smd circle
			(at 10.659872 7.649972 180)
			(size 0.450088 0.450088)
			(layers "F.Cu" "F.Mask" "F.Paste")
			(net "PVDDCR_CPU1_P1")
		)
		(pad "BN51" smd circle
			(at 11.599926 7.649972 180)
			(size 0.450088 0.450088)
			(layers "F.Cu" "F.Mask" "F.Paste")
			(net "GND")
		)
		(pad "BN52" smd circle
			(at 12.53998 7.649972 180)
			(size 0.450088 0.450088)
			(layers "F.Cu" "F.Mask" "F.Paste")
			(net "PVDD_33_S5")
		)
		(pad "BN53" smd circle
			(at 13.480034 7.649972 180)
			(size 0.450088 0.450088)
			(layers "F.Cu" "F.Mask" "F.Paste")
			(net "GND")
		)
		(pad "BN54" smd circle
			(at 14.420088 7.649972 180)
			(size 0.450088 0.450088)
			(layers "F.Cu" "F.Mask" "F.Paste")
			(net "PVDDIO_P1")
		)
		(pad "BN55" smd circle
			(at 15.359888 7.649972 180)
			(size 0.450088 0.450088)
			(layers "F.Cu" "F.Mask" "F.Paste")
			(net "M_C_CPU1_SA_RSP<0>")
		)
		(pad "BN56" smd circle
			(at 16.299942 7.649972 180)
			(size 0.450088 0.450088)
			(layers "F.Cu" "F.Mask" "F.Paste")
			(net "GND")
		)
		(pad "BN57" smd circle
			(at 17.239996 7.649972 180)
			(size 0.450088 0.450088)
			(layers "F.Cu" "F.Mask" "F.Paste")
			(net "M_C_CPU1_SB_CS_N<1>")
		)
		(pad "BN58" smd circle
			(at 18.18005 7.649972 180)
			(size 0.450088 0.450088)
			(layers "F.Cu" "F.Mask" "F.Paste")
			(net "GND")
		)
		(pad "BN59" smd circle
			(at 19.120104 7.649972 180)
			(size 0.450088 0.450088)
			(layers "F.Cu" "F.Mask" "F.Paste")
			(net "M_D_CPU1_SA_RSP<0>")
		)
		(pad "BN60" smd circle
			(at 20.059904 7.649972 180)
			(size 0.450088 0.450088)
			(layers "F.Cu" "F.Mask" "F.Paste")
			(net "M_D_CPU1_SB_CS_N<1>")
		)
		(pad "BN61" smd circle
			(at 20.999958 7.649972 180)
			(size 0.450088 0.450088)
			(layers "F.Cu" "F.Mask" "F.Paste")
			(net "GND")
		)
	)
)
